FILE_TYPE = CONNECTIVITY;
{Allegro Design Entry HDL 17.2-2016 S081 (4005846) 1/11/2022}
"PAGE_NUMBER" = 185;
0"NC";
1"GND\g";
2"GND\g";
3"GND\g";
4"GND\g";
5"GND\g";
6"GND\g";
7"GND\g";
8"GND\g";
9"GND\g";
10"GND\g";
11"GND\g";
12"GND\g";
13"GND\g";
14"GND\g";
15"GND\g";
16"GND\g";
17"GND\g";
18"GND\g";
19"PVDDCR_CPU0_P1\g";
20"PVDDCR_SOC_P1\g";
21"GND\g";
22"VSENSE_VSS_SENSE_A_P1";
23"VSENSE_PVDDCR_SOC_P1_DP";
24"VSENSE_VSS_SENSE_A_P1";
25"VSENSE_PVDDCR_CPU0_P1_DP";
26"PVDDCR_SOC_P1_PWM3";
27"PVDDCR_SOC_P1_IMON3";
28"P3V3_STBY\g";
29"PVDDCR_CPU0_P1_VCC";
30"PVDDCR_CPU0_P1_PWM3";
31"PVDDCR_CPU0_P1_IMON2";
32"PVDDCR_CPU0_P1_PWM2";
33"PVDDCR_CPU0_P1_IMON1";
34"PVDDCR_CPU0_P1_PWM1";
35"PVDDCR_CPU0_P1_VCCS";
36"GND\g";
37"GND\g";
38"PVDDCR_CPU0_P1_IMON6";
39"PVDDCR_SOC_P1_PWM2";
40"NC_PVDDCR_CPU0_P1_PWM9";
41"NC_PVDDCR_CPU0_P1_IMON7";
42"NC_PVDDCR_CPU0_P1_PWM8";
43"NC_PVDDCR_CPU0_P1_IMON8";
44"NC_PVDDCR_CPU0_P1_IMON9";
45"PVDDCR_SOC_P1_TEMP1";
46"PVDDCR_SOC_P1_IMON1";
47"PVDDCR_SOC_P1_PWM1";
48"PVDDCR_SOC_P1_IMON2";
49"PVDDCR_CPU0_P1_TEMP0";
50"GND\g";
51"PWRGD_PVDDCR_CPU0_P1_R";
52"GND\g";
53"PVDDCR_CPU0_P1_PMSCL_R";
54"SVID_PVDDCR_CPU0_P1_SVTI_R";
55"SVID_PVDDCR_CPU0_P1_SVTO_R";
56"PVDDCR_CPU0_P1_PMALERT_R";
57"PVDDCR_CPU0_P1_EN_R";
58"PVDDCR_CPU0_P1_PMALERT";
59"SMB_SCM_6_R2_SDA";
60"SMB_SCM_6_R2_SCL";
61"PWRGD_PVDDCR_CPU0_P1";
62"PVDDCR_CPU0_P1_EN";
63"P3V3_STBY\g";
64"SVID_PVDDCR_CPU0_P1_SVC_R";
65"SVID_PVDDCR_CPU0_P1_SVD_R";
66"VSENSE_PVDDCR_CPU0_P1_VSEN0";
67"VSENSE_PVDDCR_SOC_P1_VSEN1";
68"PVDDCR_CPU0_P1_RESET_N_R";
69"PVDDCR_CPU0_P1_OCP_N_R";
70"GND\g";
71"GND\g";
72"PVDD18_S5_P1\g";
73"P12V_STBY\g";
74"PVDDCR_SOC_P1_EN//ADDR_CFG";
75"PVDD18_S5_P1\g";
76"PVDDCR_CPU0_P1_RESET_N";
77"PVDDCR_CPU0_P1_OCP_N";
78"P3V3_STBY\g";
79"P3V3_STBY\g";
80"GND\g";
81"PVDDCR_SOC_P1_EN_GD";
82"PVDDCR_SOC_P1_EN_RC";
83"P5V_STBY\g";
84"PVDD18_S5_P1\g";
85"SVID_PVDDCR_CPU0_P1_SVTO";
86"SVID_PVDDCR_CPU0_P1_SVTI";
87"PVDDCR_SOC_P1_EN";
88"PVDDCR_CPU0_P1_VINSEN";
89"PWRGD_PVDDCR_SOC_P1";
90"PVDDCR_CPU0_P1_IMON5";
91"PVDDCR_CPU0_P1_IMON4";
92"PVDDCR_CPU0_P1_PMSDA_R";
93"PVDDCR_CPU0_P1_PWM5";
94"PVDDCR_CPU0_P1_PWM4";
95"PVDDCR_CPU0_P1_IMON3";
96"PVDDCR_CPU0_P1_PWM6";
97"NC_PVDDCR_CPU0_P1_PWM7";
98"GND\g";
99"PWRGD_PVDDCR_SOC_P1_R";
100"PVDDCR_CPU0_P1_VMON";
%"MOSFET_N"
"1","(-7825,1525)","0","pure_quanta","I1";
;
LOCATION"PQ15"
$SEC"1"
CDS_SEC"1"
MATERIAL"IC"
VALUE"BSS138K"
PART_NUMBER"BAM138K0000"
MANUF_PN"BSS138K"
CDS_LMAN_SYM_OUTLINE"-50,50,100,-150"
CDS_LIB"pure_quanta"
PACK_TYPE"SMLF";
"GATE"
$PN"G"82;
"SOURCE"
$PN"S"80;
"DRAIN"
$PN"D"81;
%"UNIVERSAL_GND"
"1","(-2900,5875)","0","pure_quanta_power","I10";
;
CDS_LIB"pure_quanta_power"
HDL_POWER"GND";
"A"1;
%"Q_CAP"
"1","(-5300,475)","0","pure_quanta","I100";
;
LOCATION"PC6"
SEC"1"
MATERIAL"X7R"
TOLERANCE"10%"
VALUE"0.1UF"
PART_NUMBER"CH4104K1B00"
VOLTAGE"25V"
PACK_TYPE"0402"
CDS_LIB"pure_quanta"
SEC_TYPE"0402";
"B"
$PN"2"2;
"A"
$PN"1"88;
%"Q_RES"
"1","(-5950,650)","0","pure_quanta","I101";
;
LOCATION"PR181"
$SEC"1"
CDS_SEC"1"
MATERIAL"CHIP"
PART_NUMBER"CS00002JB38"
WATTAGE"1/16W"
TOLERANCE"5%"
VALUE"0"
PACK_TYPE"0402LF"
CDS_LIB"pure_quanta";
"B"
$PN"2"88;
"A"
$PN"1"73;
%"UNIVERSAL_GND"
"1","(-5300,250)","0","pure_quanta_power","I102";
;
CDS_LIB"pure_quanta_power"
HDL_POWER"GND";
"A"2;
%"VCC_CORE"
"1","(-6200,725)","0","pure_quanta_power","I103";
;
HDL_POWER"P12V_STBY"
CDS_LIB"pure_quanta_power";
"A"73;
%"Q_RES"
"1","(-7250,825)","0","pure_quanta","I104";
;
LOCATION"PR157"
$SEC"1"
CDS_SEC"1"
WATTAGE"1/16W"
MATERIAL"CHIP"
TOLERANCE"1%"
VALUE"40.2K"
PART_NUMBER"TMP_QCS34022FB15"
PACK_TYPE"0402LF"
CDS_LIB"pure_quanta";
"B"
$PN"2"100;
"A"
$PN"1"83;
%"Q_RES"
"2","(-6950,650)","0","pure_quanta","I105";
;
LOCATION"PR4"
SEC"1"
WATTAGE"1/16W"
MATERIAL"CHIP"
TOLERANCE"1%"
VALUE"10K"
PART_NUMBER"TMP_QCS31002FB26"
PACK_TYPE"0402LF"
SEC_TYPE"0402LF"
CDS_LIB"pure_quanta";
"A"
$PN"1"100;
"B"
$PN"2"3;
%"UNIVERSAL_GND"
"1","(-6950,400)","0","pure_quanta_power","I107";
;
CDS_LIB"pure_quanta_power"
HDL_POWER"GND";
"A"3;
%"UNIVERSAL_GND"
"1","(-6475,400)","0","pure_quanta_power","I108";
;
CDS_LIB"pure_quanta_power"
HDL_POWER"GND";
"A"4;
%"VCC_CORE"
"1","(-7550,950)","0","pure_quanta_power","I109";
;
HDL_POWER"P5V_STBY"
CDS_LIB"pure_quanta_power";
"A"83;
%"VCC_CORE"
"1","(-6600,1400)","0","pure_quanta_power","I111";
;
HDL_POWER"P3V3_STBY"
CDS_LIB"pure_quanta_power";
"A"79;
%"Q_RES"
"1","(-6325,1250)","0","pure_quanta","I112";
;
LOCATION"PR165"
$SEC"1"
CDS_SEC"1"
MATERIAL"CHIP"
WATTAGE"1/16W"
TOLERANCE"1%"
VALUE"1K"
PART_NUMBER"TMP_QCS21002FB24"
PACK_TYPE"0402LF"
CDS_LIB"pure_quanta";
"B"
$PN"2"99;
"A"
$PN"1"79;
%"Q_RES"
"1","(-6325,1000)","0","pure_quanta","I113";
;
LOCATION"PR166"
$SEC"1"
CDS_SEC"1"
PACK_TYPE"0402LF"
WATTAGE"1/16W"
MATERIAL"CHIP"
TOLERANCE"5%"
VALUE"0"
PART_NUMBER"CS00002JB38"
CDS_LIB"pure_quanta";
"B"
$PN"2"99;
"A"
$PN"1"89;
%"Q_CAP"
"2","(-5650,1250)","0","pure_quanta","I114";
;
LOCATION"PC246"
$SEC"1"
CDS_SEC"1"
MATERIAL"EMPTY"
TOLERANCE"5%"
VALUE"1000PF"
PART_NUMBER"TMP_QCH21006JB10"
VOLTAGE"50V"
PACK_TYPE"0402"
CDS_LIB"pure_quanta";
"A"
$PN"1"99;
"B"
$PN"2"71;
%"UNIVERSAL_GND"
"1","(-5325,1125)","0","pure_quanta_power","I116";
;
CDS_LIB"pure_quanta_power"
HDL_POWER"GND";
"A"71;
%"Q_CAP"
"1","(-6475,650)","0","pure_quanta","I118";
;
LOCATION"PC243"
$SEC"1"
CDS_SEC"1"
PACK_TYPE"0402"
PART_NUMBER"CH4104K1B00"
VALUE"0.1UF"
MATERIAL"X7R"
TOLERANCE"10%"
VOLTAGE"25V"
CDS_LIB"pure_quanta";
"B"
$PN"2"4;
"A"
$PN"1"100;
%"UNIVERSAL_GND"
"1","(-2925,5425)","0","pure_quanta_power","I12";
;
CDS_LIB"pure_quanta_power"
HDL_POWER"GND";
"A"5;
%"Q_CAP"
"1","(-2925,5650)","0","pure_quanta","I13";
;
LOCATION"PC251"
$SEC"1"
CDS_SEC"1"
MATERIAL"X6S"
TOLERANCE"20%"
VALUE"10UF"
PART_NUMBER"CH6101MEB01"
VOLTAGE"6.3V"
PACK_TYPE"C0402"
CDS_LIB"pure_quanta";
"B"
$PN"2"5;
"A"
$PN"1"35;
%"Q_RES"
"1","(-8600,1425)","0","pure_quanta","I139";
;
LOCATION"PR149"
$SEC"1"
CDS_SEC"1"
WATTAGE"1/16W"
MATERIAL"CHIP"
TOLERANCE"5%"
VALUE"0"
PART_NUMBER"CS00002JB38"
PACK_TYPE"0402LF"
CDS_LIB"pure_quanta";
"B"
$PN"2"82;
"A"
$PN"1"87;
%"VCC_CORE"
"1","(-2050,6375)","0","pure_quanta_power","I14";
;
HDL_POWER"P3V3_STBY"
CDS_LIB"pure_quanta_power";
"A"28;
%"Q_CAP"
"1","(-8175,1225)","0","pure_quanta","I140";
;
LOCATION"PC242"
$SEC"1"
CDS_SEC"1"
MATERIAL"X7R"
TOLERANCE"5%"
VALUE"1000PF"
PART_NUMBER"TMP_QCH21006JB10"
VOLTAGE"50V"
PACK_TYPE"0402"
CDS_LIB"pure_quanta";
"B"
$PN"2"6;
"A"
$PN"1"82;
%"UNIVERSAL_GND"
"1","(-8175,1000)","0","pure_quanta_power","I141";
;
CDS_LIB"pure_quanta_power"
HDL_POWER"GND";
"A"6;
%"UNIVERSAL_GND"
"1","(-7825,4775)","0","pure_quanta_power","I144";
;
CDS_LIB"pure_quanta_power"
HDL_POWER"GND";
"A"7;
%"UNIVERSAL_GND"
"1","(-7550,4775)","0","pure_quanta_power","I145";
;
CDS_LIB"pure_quanta_power"
HDL_POWER"GND";
"A"8;
%"Q_RES"
"1","(-6025,5350)","0","pure_quanta","I148";
;
LOCATION"PR171"
$SEC"1"
CDS_SEC"1"
WATTAGE"1/16W"
MATERIAL"CHIP"
TOLERANCE"5%"
VALUE"0"
PART_NUMBER"CS00002JB38"
PACK_TYPE"0402LF"
CDS_LIB"pure_quanta";
"B"
$PN"2"55;
"A"
$PN"1"85;
%"Q_RES"
"1","(-6025,5200)","0","pure_quanta","I149";
;
LOCATION"PR172"
$SEC"1"
CDS_SEC"1"
WATTAGE"1/16W"
MATERIAL"CHIP"
TOLERANCE"5%"
VALUE"0"
PART_NUMBER"CS00002JB38"
PACK_TYPE"0402LF"
CDS_LIB"pure_quanta";
"B"
$PN"2"54;
"A"
$PN"1"86;
%"Q_RES"
"1","(-2475,6275)","0","pure_quanta","I151";
;
LOCATION"PR183"
$SEC"1"
CDS_SEC"1"
WATTAGE"1/16W"
MATERIAL"CHIP"
TOLERANCE"1%"
VALUE"1"
PART_NUMBER"CS-1002FB23"
PACK_TYPE"0402LF"
CDS_LIB"pure_quanta";
"B"
$PN"2"28;
"A"
$PN"1"29;
%"MOSFET_PCH_GDS_ESD_PROTECTED"
"1","(-7125,1850)","6","pure_quanta","I154";
;
LOCATION"PQ11"
$SEC"1"
CDS_SEC"1"
MATERIAL"IC"
VALUE"PJA3415AE"
PART_NUMBER"BAM34150008"
CDS_LIB"pure_quanta"
CDS_LMAN_SYM_OUTLINE"-125,150,125,-150"
NEEDS_NO_SIZE"TRUE"
PART_TYPE"SMLF";
"S"
$PN"S"78;
"G"
$PN"G"81;
"D"
$PN"D"74;
%"UNIVERSAL_GND"
"1","(-3250,5425)","0","pure_quanta_power","I155";
;
CDS_LIB"pure_quanta_power"
HDL_POWER"GND";
"A"9;
%"Q_CAP"
"1","(-3250,5650)","0","pure_quanta","I156";
;
LOCATION"PC11"
$SEC"1"
CDS_SEC"1"
MATERIAL"X7R"
TOLERANCE"10%"
VALUE"0.1UF"
PART_NUMBER"CH4104K1B00"
VOLTAGE"25V"
PACK_TYPE"0402"
CDS_LIB"pure_quanta";
"B"
$PN"2"9;
"A"
$PN"1"35;
%"UNIVERSAL_GND"
"1","(-3250,5875)","0","pure_quanta_power","I157";
;
CDS_LIB"pure_quanta_power"
HDL_POWER"GND";
"A"10;
%"Q_CAP"
"1","(-3250,6125)","0","pure_quanta","I158";
;
LOCATION"PC10"
$SEC"1"
CDS_SEC"1"
MATERIAL"X7R"
TOLERANCE"10%"
VALUE"0.1UF"
PART_NUMBER"CH4104K1B00"
VOLTAGE"25V"
PACK_TYPE"0402"
CDS_LIB"pure_quanta";
"B"
$PN"2"10;
"A"
$PN"1"29;
%"VCC_CORE"
"1","(-6225,1800)","0","pure_quanta_power","I174";
;
HDL_POWER"PVDD18_S5_P1"
CDS_LIB"pure_quanta_power";
"A"72;
%"Q_CAP"
"2","(-5675,1725)","0","pure_quanta","I175";
;
LOCATION"PC247"
$SEC"1"
CDS_SEC"1"
MATERIAL"X7R"
TOLERANCE"10%"
VALUE"1UF"
PART_NUMBER"CH5101K1B01"
VOLTAGE"6.3V"
PACK_TYPE"0402"
CDS_LIB"pure_quanta";
"A"
$PN"1"72;
"B"
$PN"2"11;
%"VCC_CORE"
"1","(-6525,2525)","0","pure_quanta_power","I177";
;
HDL_POWER"PVDD18_S5_P1"
CDS_LIB"pure_quanta_power";
"A"75;
%"Q_RES"
"1","(-6050,2100)","0","pure_quanta","I178";
;
LOCATION"PR168"
$SEC"1"
CDS_SEC"1"
WATTAGE"1/16W"
MATERIAL"CHIP"
TOLERANCE"5%"
VALUE"0"
PART_NUMBER"CS00002JB38"
PACK_TYPE"0402LF"
CDS_LIB"pure_quanta";
"B"
$PN"2"69;
"A"
$PN"1"77;
%"Q_RES"
"1","(-6050,2250)","0","pure_quanta","I179";
;
LOCATION"PR182"
$SEC"1"
CDS_SEC"1"
WATTAGE"1/16W"
MATERIAL"CHIP"
TOLERANCE"5%"
VALUE"0"
PART_NUMBER"CS00002JB38"
PACK_TYPE"0402LF"
CDS_LIB"pure_quanta";
"B"
$PN"2"68;
"A"
$PN"1"76;
%"Q_RES"
"1","(-6075,2400)","0","pure_quanta","I180";
;
LOCATION"PR184"
$SEC"1"
CDS_SEC"1"
WATTAGE"1/16W"
MATERIAL"CHIP"
TOLERANCE"1%"
VALUE"1K"
PART_NUMBER"TMP_QCS21002FB24"
PACK_TYPE"0402LF"
CDS_LIB"pure_quanta";
"B"
$PN"2"68;
"A"
$PN"1"75;
%"Q_RES"
"1","(-5400,1975)","0","pure_quanta","I181";
;
LOCATION"PR180"
$SEC"1"
CDS_SEC"1"
WATTAGE"1/16W"
MATERIAL"CHIP"
TOLERANCE"1%"
VALUE"1K"
PART_NUMBER"TMP_QCS21002FB24"
PACK_TYPE"0402LF"
CDS_LIB"pure_quanta";
"B"
$PN"2"69;
"A"
$PN"1"72;
%"UNIVERSAL_GND"
"1","(-5275,1725)","1","pure_quanta_power","I182";
;
CDS_LIB"pure_quanta_power"
HDL_POWER"GND";
"A"11;
%"Q_RES"
"2","(-8525,5025)","0","pure_quanta","I185";
;
LOCATION"PR150"
$SEC"1"
CDS_SEC"1"
WATTAGE"1/16W"
MATERIAL"CHIP"
TOLERANCE"5%"
VALUE"1K"
PACK_TYPE"0402LF"
CDS_LIB"pure_quanta"
PART_NUMBER"TMP_QCS21002JB34";
"A"
$PN"1"86;
"B"
$PN"2"16;
%"Q_RES"
"1","(-6125,6375)","0","pure_quanta","I186";
;
LOCATION"PR167"
$SEC"1"
CDS_SEC"1"
WATTAGE"1/16W"
MATERIAL"CHIP"
TOLERANCE"1%"
VALUE"1K"
PART_NUMBER"TMP_QCS21002FB24"
PACK_TYPE"0402LF"
CDS_LIB"pure_quanta";
"B"
$PN"2"51;
"A"
$PN"1"63;
%"Q_RES"
"1","(-5925,4950)","0","pure_quanta","I187";
;
LOCATION"PR175"
$SEC"1"
CDS_SEC"1"
WATTAGE"1/16W"
MATERIAL"CHIP"
TOLERANCE"5%"
VALUE"0"
PART_NUMBER"CS00002JB38"
PACK_TYPE"0402LF"
CDS_LIB"pure_quanta";
"B"
$PN"2"53;
"A"
$PN"1"60;
%"Q_CAP"
"1","(-7550,5025)","0","pure_quanta","I214";
;
LOCATION"PC297"
$SEC"1"
CDS_SEC"1"
MATERIAL"EMPTY"
TOLERANCE"5%"
VALUE"10PF"
PART_NUMBER"CH01006JB08"
VOLTAGE"50V"
PACK_TYPE"0402"
CDS_LIB"pure_quanta";
"B"
$PN"2"8;
"A"
$PN"1"64;
%"Q_CAP"
"1","(-7825,5025)","0","pure_quanta","I215";
;
LOCATION"PC296"
$SEC"1"
CDS_SEC"1"
MATERIAL"EMPTY"
TOLERANCE"5%"
VALUE"10PF"
VOLTAGE"50V"
PACK_TYPE"0402"
CDS_LIB"pure_quanta"
PART_NUMBER"CH01006JB08";
"B"
$PN"2"7;
"A"
$PN"1"65;
%"UNIVERSAL_GND"
"1","(-8050,4775)","0","pure_quanta_power","I216";
;
CDS_LIB"pure_quanta_power"
HDL_POWER"GND";
"A"12;
%"Q_CAP"
"1","(-8050,5025)","0","pure_quanta","I217";
;
LOCATION"PC295"
$SEC"1"
CDS_SEC"1"
MATERIAL"EMPTY"
TOLERANCE"5%"
VALUE"10PF"
VOLTAGE"50V"
PACK_TYPE"0402"
CDS_LIB"pure_quanta"
PART_NUMBER"CH01006JB08";
"B"
$PN"2"12;
"A"
$PN"1"85;
%"Q_RES"
"1","(-2825,3200)","0","pure_quanta","I230";
;
LOCATION"PR530"
$SEC"1"
CDS_SEC"1"
PACK_TYPE"0402LF"
VALUE"0"
WATTAGE"1/16W"
MATERIAL"CHIP"
TOLERANCE"5%"
PART_NUMBER"CS00002JB38"
CDS_LIB"pure_quanta";
"B"
$PN"2"36;
"A"
$PN"1"41;
%"UNIVERSAL_GND"
"1","(-2500,3075)","0","pure_quanta_power","I231";
;
CDS_LIB"pure_quanta_power"
HDL_POWER"GND";
"A"36;
%"UNIVERSAL_GND"
"1","(-2500,2775)","0","pure_quanta_power","I232";
;
CDS_LIB"pure_quanta_power"
HDL_POWER"GND";
"A"98;
%"Q_RES"
"1","(-2825,2900)","0","pure_quanta","I233";
;
LOCATION"PR436"
$SEC"1"
CDS_SEC"1"
WATTAGE"1/16W"
MATERIAL"CHIP"
TOLERANCE"5%"
VALUE"0"
PART_NUMBER"CS00002JB38"
PACK_TYPE"0402LF"
CDS_LIB"pure_quanta";
"B"
$PN"2"98;
"A"
$PN"1"43;
%"UNIVERSAL_GND"
"1","(-2500,2475)","0","pure_quanta_power","I240";
;
CDS_LIB"pure_quanta_power"
HDL_POWER"GND";
"A"37;
%"Q_RES"
"1","(-2825,2600)","0","pure_quanta","I241";
;
LOCATION"PR437"
$SEC"1"
CDS_SEC"1"
WATTAGE"1/16W"
MATERIAL"CHIP"
TOLERANCE"5%"
VALUE"0"
PART_NUMBER"CS00002JB38"
PACK_TYPE"0402LF"
CDS_LIB"pure_quanta";
"B"
$PN"2"37;
"A"
$PN"1"44;
%"UNIVERSAL_GND"
"1","(-5625,250)","0","pure_quanta_power","I242";
;
CDS_LIB"pure_quanta_power"
HDL_POWER"GND";
"A"13;
%"Q_RES"
"2","(-5625,450)","0","pure_quanta","I243";
;
LOCATION"PR602"
$SEC"1"
CDS_SEC"1"
WATTAGE"1/16W"
MATERIAL"EMPTY"
TOLERANCE"1%"
VALUE"4.99K"
PART_NUMBER"CS24992FB07"
PACK_TYPE"0402LF"
CDS_LIB"pure_quanta";
"A"
$PN"1"88;
"B"
$PN"2"13;
%"Q_RES"
"2","(-7100,1375)","0","pure_quanta","I3";
;
LOCATION"PR159"
$SEC"1"
CDS_SEC"1"
WATTAGE"1/16W"
MATERIAL"CHIP"
TOLERANCE"1%"
VALUE"6.65K"
PART_NUMBER"TMP_QCS26652FB06"
PACK_TYPE"0402LF"
CDS_LIB"pure_quanta";
"A"
$PN"1"74;
"B"
$PN"2"80;
%"Q_CAP"
"1","(-2750,1025)","0","pure_quanta","I35";
;
LOCATION"PC253"
$SEC"1"
CDS_SEC"1"
MATERIAL"X7R"
TOLERANCE"10%"
VALUE"470PF"
PART_NUMBER"TMP_QCH14706KB18"
VOLTAGE"50V"
PACK_TYPE"0402"
CDS_LIB"pure_quanta";
"B"
$PN"2"15;
"A"
$PN"1"45;
%"Q_CAP"
"1","(-3375,700)","0","pure_quanta","I36";
;
LOCATION"PC250"
$SEC"1"
CDS_SEC"1"
MATERIAL"X7R"
TOLERANCE"10%"
VALUE"470PF"
PART_NUMBER"TMP_QCH14706KB18"
VOLTAGE"50V"
PACK_TYPE"0402"
CDS_LIB"pure_quanta";
"B"
$PN"2"14;
"A"
$PN"1"49;
%"UNIVERSAL_GND"
"1","(-3375,425)","0","pure_quanta_power","I37";
;
CDS_LIB"pure_quanta_power"
HDL_POWER"GND";
"A"14;
%"UNIVERSAL_GND"
"1","(-2750,775)","0","pure_quanta_power","I38";
;
CDS_LIB"pure_quanta_power"
HDL_POWER"GND";
"A"15;
%"Q_RES"
"2","(-7775,2075)","0","pure_quanta","I4";
;
LOCATION"PR152"
$SEC"1"
CDS_SEC"1"
WATTAGE"1/16W"
MATERIAL"CHIP"
TOLERANCE"1%"
VALUE"1K"
PART_NUMBER"TMP_QCS21002FB24"
PACK_TYPE"0402LF"
CDS_LIB"pure_quanta";
"A"
$PN"1"78;
"B"
$PN"2"81;
%"Q_CAP"
"2","(-5250,6375)","0","pure_quanta","I42";
;
LOCATION"PC248"
$SEC"1"
CDS_SEC"1"
MATERIAL"EMPTY"
TOLERANCE"5%"
VALUE"1000PF"
PART_NUMBER"TMP_QCH21006JB10"
VOLTAGE"50V"
PACK_TYPE"0402"
CDS_LIB"pure_quanta";
"A"
$PN"1"51;
"B"
$PN"2"50;
%"Q_RES"
"1","(-5900,6100)","0","pure_quanta","I43";
;
LOCATION"PR178"
$SEC"1"
CDS_SEC"1"
WATTAGE"1/16W"
MATERIAL"CHIP"
TOLERANCE"5%"
VALUE"0"
PART_NUMBER"CS00002JB38"
PACK_TYPE"0402LF"
CDS_LIB"pure_quanta";
"B"
$PN"2"51;
"A"
$PN"1"61;
%"UNIVERSAL_GND"
"1","(-5000,6300)","0","pure_quanta_power","I44";
;
CDS_LIB"pure_quanta_power"
HDL_POWER"GND";
"A"50;
%"VCC_CORE"
"1","(-6525,6500)","0","pure_quanta_power","I46";
;
HDL_POWER"P3V3_STBY"
CDS_LIB"pure_quanta_power";
"A"63;
%"Q_RES"
"1","(-5900,5950)","0","pure_quanta","I47";
;
LOCATION"PR179"
$SEC"1"
CDS_SEC"1"
WATTAGE"1/16W"
MATERIAL"CHIP"
TOLERANCE"5%"
VALUE"0"
PART_NUMBER"CS00002JB38"
PACK_TYPE"0402LF"
CDS_LIB"pure_quanta";
"B"
$PN"2"57;
"A"
$PN"1"62;
%"Q_CAP"
"2","(-5225,5825)","0","pure_quanta","I49";
;
LOCATION"PC249"
$SEC"1"
CDS_SEC"1"
TOLERANCE"5%"
VOLTAGE"50V"
MATERIAL"X7R"
VALUE"1000PF"
PART_NUMBER"TMP_QCH21006JB10"
PACK_TYPE"0402"
CDS_LIB"pure_quanta";
"A"
$PN"1"57;
"B"
$PN"2"52;
%"UNIVERSAL_GND"
"1","(-7100,1175)","0","pure_quanta_power","I5";
;
CDS_LIB"pure_quanta_power"
HDL_POWER"GND";
"A"80;
%"UNIVERSAL_GND"
"1","(-5000,5750)","0","pure_quanta_power","I50";
;
CDS_LIB"pure_quanta_power"
HDL_POWER"GND";
"A"52;
%"Q_RES"
"2","(-8000,5975)","0","pure_quanta","I55";
;
LOCATION"PR154"
$SEC"1"
CDS_SEC"1"
WATTAGE"1/16W"
MATERIAL"EMPTY"
TOLERANCE"1%"
VALUE"1K"
PACK_TYPE"0402LF"
CDS_LIB"pure_quanta"
PART_NUMBER"TMP_QCS21002FB24";
"A"
$PN"1"84;
"B"
$PN"2"85;
%"Q_RES"
"2","(-8350,5975)","0","pure_quanta","I56";
;
LOCATION"PR151"
$SEC"1"
CDS_SEC"1"
WATTAGE"1/16W"
MATERIAL"EMPTY"
TOLERANCE"1%"
VALUE"1K"
PACK_TYPE"0402LF"
CDS_LIB"pure_quanta"
PART_NUMBER"TMP_QCS21002FB24";
"A"
$PN"1"84;
"B"
$PN"2"86;
%"Q_RES"
"2","(-7700,5975)","0","pure_quanta","I57";
;
LOCATION"PR156"
$SEC"1"
CDS_SEC"1"
WATTAGE"1/16W"
MATERIAL"EMPTY"
TOLERANCE"1%"
VALUE"1K"
PACK_TYPE"0402LF"
CDS_LIB"pure_quanta"
PART_NUMBER"TMP_QCS21002FB24";
"A"
$PN"1"84;
"B"
$PN"2"65;
%"Q_RES"
"2","(-7425,5975)","0","pure_quanta","I58";
;
LOCATION"PR160"
$SEC"1"
CDS_SEC"1"
WATTAGE"1/16W"
MATERIAL"EMPTY"
TOLERANCE"1%"
VALUE"1K"
PART_NUMBER"TMP_QCS21002FB24"
PACK_TYPE"0402LF"
CDS_LIB"pure_quanta";
"A"
$PN"1"84;
"B"
$PN"2"64;
%"VCC_CORE"
"1","(-8350,6275)","0","pure_quanta_power","I59";
;
HDL_POWER"PVDD18_S5_P1"
CDS_LIB"pure_quanta_power";
"A"84;
%"VCC_CORE"
"1","(-7775,2300)","0","pure_quanta_power","I6";
;
HDL_POWER"P3V3_STBY"
CDS_LIB"pure_quanta_power";
"A"78;
%"Q_RES"
"2","(-8250,5025)","0","pure_quanta","I62";
;
LOCATION"PR153"
$SEC"1"
CDS_SEC"1"
WATTAGE"1/16W"
MATERIAL"EMPTY"
TOLERANCE"1%"
VALUE"1K"
PACK_TYPE"0402LF"
CDS_LIB"pure_quanta"
PART_NUMBER"TMP_QCS21002FB24";
"A"
$PN"1"85;
"B"
$PN"2"17;
%"UNIVERSAL_GND"
"1","(-8525,4775)","0","pure_quanta_power","I64";
;
CDS_LIB"pure_quanta_power"
HDL_POWER"GND";
"A"16;
%"UNIVERSAL_GND"
"1","(-8250,4775)","0","pure_quanta_power","I65";
;
CDS_LIB"pure_quanta_power"
HDL_POWER"GND";
"A"17;
%"Q_RES"
"1","(-5925,4800)","0","pure_quanta","I67";
;
LOCATION"PR176"
$SEC"1"
CDS_SEC"1"
WATTAGE"1/16W"
MATERIAL"CHIP"
TOLERANCE"5%"
VALUE"0"
PART_NUMBER"CS00002JB38"
PACK_TYPE"0402LF"
CDS_LIB"pure_quanta";
"B"
$PN"2"92;
"A"
$PN"1"59;
%"Q_RES"
"1","(-5925,4650)","0","pure_quanta","I68";
;
LOCATION"PR177"
$SEC"1"
CDS_SEC"1"
WATTAGE"1/16W"
MATERIAL"CHIP"
TOLERANCE"5%"
VALUE"0"
PART_NUMBER"CS00002JB38"
PACK_TYPE"0402LF"
CDS_LIB"pure_quanta";
"B"
$PN"2"56;
"A"
$PN"1"58;
%"RAA229620GNPHA0"
"1","(-4300,3350)","0","pure_quanta","I7";
;
LOCATION"PU25"
SEC"1"
PART_NUMBER"AR0T6GPV005"
VALUE"RAA229620GNP#HA0"
MATERIAL"IC"
PART_TYPE"SMLF"
SEC_TYPE""
CDS_LMAN_SYM_OUTLINE"-550,2850,500,-2850"
NEEDS_NO_SIZE"TRUE"
CDS_LIB"pure_quanta";
"CS10"
$PN"28"31;
"PWM10"
$PN"11"32;
"CS9"
$PN"29"95;
"PWM9"
$PN"10"30;
"CS8"
$PN"30"91;
"PWM8"
$PN"9"94;
"CS7"
$PN"31"90;
"PWM7"
$PN"8"93;
"CS0"
$PN"38"46;
"PWM0"
$PN"1"47;
"TEMP1"
$PN"43"45;
"EN1||ADDR_CFG"
$PN"42"74;
"TH_GND"
$PN"TH"70;
"OCP_L \B"
$PN"41"69;
"CS2"
$PN"36"27;
"PWM2"
$PN"3"26;
"CS3"
$PN"35"44;
"PWM3"
$PN"4"40;
"PWM11"
$PN"12"34;
"CS1"
$PN"37"48;
"RGND1"
$PN"39"22;
"VSEN1"
$PN"40"67;
"VDDIO"
$PN"19"72;
"TEMP0"
$PN"44"49;
"VINSEN"
$PN"46"88;
"VMON||IINSEN"
$PN"45"100;
"VCCS"
$PN"48"35;
"PWM6"
$PN"7"96;
"PG0"
$PN"16"51;
"PWM1"
$PN"2"39;
"VSEN0"
$PN"25"66;
"PWM5"
$PN"6"97;
"PWM4"
$PN"5"42;
"PMSDA"
$PN"13"92;
"RGND0"
$PN"26"24;
"EN0"
$PN"17"57;
"NPMALERT \B"
$PN"15"56;
"SVD"
$PN"21"65;
"PG1"
$PN"20"99;
"CS4"
$PN"34"43;
"CS5"
$PN"33"41;
"RESET_L \B"
$PN"18"68;
"SVTO"
$PN"23"55;
"CS6"
$PN"32"38;
"SVC"
$PN"22"64;
"PMSCL"
$PN"14"53;
"SVTI"
$PN"24"54;
"VCC"
$PN"47"29;
"CS11"
$PN"27"33;
%"Q_CAP"
"1","(-5750,3925)","0","pure_quanta","I76";
;
LOCATION"PC244"
$SEC"1"
CDS_SEC"1"
MATERIAL"X7R"
TOLERANCE"10%"
VALUE"3300PF"
PART_NUMBER"TMP_QCH2336K1B12"
VOLTAGE"50V"
PACK_TYPE"0402"
CDS_LIB"pure_quanta";
"B"
$PN"2"24;
"A"
$PN"1"66;
%"Q_RES"
"1","(-6025,4050)","0","pure_quanta","I77";
;
LOCATION"PR173"
$SEC"1"
CDS_SEC"1"
WATTAGE"1/16W"
MATERIAL"CHIP"
TOLERANCE"1%"
VALUE"10"
PART_NUMBER"TMP_QCS01002FB21"
PACK_TYPE"0402LF"
CDS_LIB"pure_quanta";
"B"
$PN"2"66;
"A"
$PN"1"25;
%"Q_CAP"
"1","(-2900,6125)","0","pure_quanta","I8";
;
LOCATION"PC252"
$SEC"1"
CDS_SEC"1"
MATERIAL"X6S"
TOLERANCE"10%"
VALUE"1UF"
PART_NUMBER"CH5103KEB01"
VOLTAGE"16V"
PACK_TYPE"C0402"
CDS_LIB"pure_quanta";
"B"
$PN"2"1;
"A"
$PN"1"29;
%"Q_RES"
"2","(-7100,4250)","0","pure_quanta","I81";
;
LOCATION"PR161"
$SEC"1"
CDS_SEC"1"
WATTAGE"1/16W"
MATERIAL"CHIP"
PART_NUMBER"CS04992FB31"
PACK_TYPE"0402LF"
VALUE"49.9"
TOLERANCE"1%"
CDS_LIB"pure_quanta";
"A"
$PN"1"19;
"B"
$PN"2"25;
%"Q_RES"
"2","(-7100,3625)","0","pure_quanta","I82";
;
LOCATION"PR162"
$SEC"1"
CDS_SEC"1"
WATTAGE"1/16W"
MATERIAL"CHIP"
PART_NUMBER"CS04992FB31"
PACK_TYPE"0402LF"
VALUE"49.9"
TOLERANCE"1%"
CDS_LIB"pure_quanta";
"A"
$PN"1"24;
"B"
$PN"2"18;
%"UNIVERSAL_GND"
"1","(-7100,3425)","0","pure_quanta_power","I83";
;
CDS_LIB"pure_quanta_power"
HDL_POWER"GND";
"A"18;
%"VCC_CORE"
"1","(-7100,4450)","0","pure_quanta_power","I84";
;
HDL_POWER"PVDDCR_CPU0_P1"
CDS_LIB"pure_quanta_power";
"A"19;
%"VCC_CORE"
"1","(-7100,3300)","0","pure_quanta_power","I85";
;
HDL_POWER"PVDDCR_SOC_P1"
CDS_LIB"pure_quanta_power";
"A"20;
%"Q_RES"
"2","(-7100,3125)","0","pure_quanta","I86";
;
LOCATION"PR163"
$SEC"1"
CDS_SEC"1"
WATTAGE"1/16W"
MATERIAL"CHIP"
PART_NUMBER"CS04992FB31"
PACK_TYPE"0402LF"
VALUE"49.9"
TOLERANCE"1%"
CDS_LIB"pure_quanta";
"A"
$PN"1"20;
"B"
$PN"2"23;
%"Q_CAP"
"1","(-5675,2825)","0","pure_quanta","I87";
;
LOCATION"PC245"
$SEC"1"
CDS_SEC"1"
MATERIAL"X7R"
TOLERANCE"10%"
VALUE"3300PF"
PART_NUMBER"TMP_QCH2336K1B12"
VOLTAGE"50V"
PACK_TYPE"0402"
CDS_LIB"pure_quanta";
"B"
$PN"2"22;
"A"
$PN"1"67;
%"Q_RES"
"1","(-5950,2950)","0","pure_quanta","I88";
;
LOCATION"PR174"
$SEC"1"
CDS_SEC"1"
WATTAGE"1/16W"
MATERIAL"CHIP"
TOLERANCE"1%"
VALUE"10"
PART_NUMBER"TMP_QCS01002FB21"
PACK_TYPE"0402LF"
CDS_LIB"pure_quanta";
"B"
$PN"2"67;
"A"
$PN"1"23;
%"Q_RES"
"2","(-7100,2525)","0","pure_quanta","I90";
;
LOCATION"PR164"
$SEC"1"
CDS_SEC"1"
WATTAGE"1/16W"
MATERIAL"CHIP"
PART_NUMBER"CS04992FB31"
PACK_TYPE"0402LF"
VALUE"49.9"
TOLERANCE"1%"
CDS_LIB"pure_quanta";
"A"
$PN"1"22;
"B"
$PN"2"21;
%"UNIVERSAL_GND"
"1","(-7100,2325)","0","pure_quanta_power","I91";
;
CDS_LIB"pure_quanta_power"
HDL_POWER"GND";
"A"21;
%"UNIVERSAL_GND"
"1","(-5100,450)","0","pure_quanta_power","I99";
;
CDS_LIB"pure_quanta_power"
HDL_POWER"GND";
"A"70;
END.
